# BASEBOARD_FAB2 (Tioga Pass) — schematic netlist excerpt (pin names and nets, part order shuffled) for the footprints in the layout excerpt that follows; sources: Cadence DE-HDL packaged netlist, KiCad conversion of Wiwynn_Tioga_Pass_MB.brd

C1G2  SC22U16V5MX-4-GP  20%  pkg SMD-BCG5  page 225 : \1\ = VR_FET_SW_P12V_STBY_PVDDQ_GHJ ; \2\ = GND
C7F6  CAP_A  0.1UF 16V 10% X7R  pkg 0402V  page 231 : A = VR_FET_SW_P12V_STBY_PVPP_ABC ; B = GND

Q1D3  NPN  MMBT3904 IC  pkg SM  page 199
  B  = TEMP_SENSOR_B
  E  = TEMP_SENSOR_E
  C  = TEMP_SENSOR_B

(kicad_pcb
	(version 20260206)
	(generator "pcbnew")
	(generator_version "10.0")
	(general
		(thickness 1.6)
		(legacy_teardrops no)
	)
	(paper "A4")
	(title_block
		(title "Wiwynn_Tioga_Pass_MB.brd")
		(comment 1 "Tioga Pass / footprints 1671-1673 of 4770")
	)
	(layers
		(0 "F.Cu" signal "TOP")
		(4 "In1.Cu" signal "L2GND")
		(6 "In2.Cu" signal "L3")
		(8 "In3.Cu" signal "L4GND")
		(10 "In4.Cu" signal "L5")
		(12 "In5.Cu" signal "L6GND")
		(14 "In6.Cu" signal "L7VCC")
		(16 "In7.Cu" signal "L8VCC")
		(18 "In8.Cu" signal "L9GND")
		(20 "In9.Cu" signal "L10")
		(22 "In10.Cu" signal "L11GND")
		(24 "In11.Cu" signal "L12")
		(26 "In12.Cu" signal "L13GND")
		(2 "B.Cu" signal "BOTTOM")
		(9 "F.Adhes" user "F.Adhesive")
		(11 "B.Adhes" user "B.Adhesive")
		(13 "F.Paste" user "Package Geometry/Pastemask Top")
		(15 "B.Paste" user "Package Geometry/Pastemask Bottom")
		(5 "F.SilkS" user "Ref Des/Silkscreen Top")
		(7 "B.SilkS" user "Ref Des/Silkscreen Bottom")
		(1 "F.Mask" user "Board Geometry/Soldermask Top")
		(3 "B.Mask" user "Board Geometry/Soldermask Bottom")
		(17 "Dwgs.User" user "User.Drawings")
		(19 "Cmts.User" user "User.Comments")
		(21 "Eco1.User" user "User.Eco1")
		(23 "Eco2.User" user "User.Eco2")
		(25 "Edge.Cuts" user "Board Geometry/Outline")
		(27 "Margin" user)
		(31 "F.CrtYd" user "Package Geometry/Place Bound Top")
		(29 "B.CrtYd" user "Package Geometry/Place Bound Bottom")
		(35 "F.Fab" user "Ref Des/Assembly Top")
		(33 "B.Fab" user "Ref Des/Assembly Bottom")
	)
	(footprint ""
		(layer "F.Cu")
		(at 5.1054 -22.2758 90)
		(property "Reference" "C1G2"
			(at 0 0 90)
			(layer "F.SilkS")
			(hide yes)
			(effects
				(font
					(size 1.27 1.27)
				)
			)
		)
		(property "Value" "*"
			(at -0.0762 -6.2357 90)
			(unlocked yes)
			(layer "F.Fab")
			(hide yes)
			(effects
				(font
					(size 1.27 1.016)
					(thickness 0.1524)
				)
			)
		)
		(property "Device Type" "SC22U16V5MX-4-GP_SMD-BCG5-SC22A"
			(at -0.0762 -8.2677 90)
			(unlocked yes)
			(layer "F.Fab")
			(hide yes)
			(effects
				(font
					(size 1.27 1.016)
					(thickness 0.1524)
				)
			)
		)
		(duplicate_pad_numbers_are_jumpers no)
		(fp_line
			(start 0.635 0)
			(end -0.635 0)
			(stroke
				(width 0.508)
				(type default)
			)
			(layer "F.SilkS")
		)
		(fp_rect
			(start -0.9652 1.778)
			(end 0.9652 -1.778)
			(stroke
				(width 0)
				(type default)
			)
			(fill no)
			(layer "F.CrtYd")
		)
		(fp_poly
			(pts
				(xy -0.9652 -1.778) (xy 0.9652 -1.778) (xy 0.9652 1.778) (xy -0.9652 1.778)
			)
			(stroke
				(width 0)
				(type default)
			)
			(fill no)
			(layer "F.Fab")
		)
		(pad "1" smd rect
			(at 0 -0.9652 90)
			(size 1.397 1.143)
			(layers "F.Cu" "F.Mask" "F.Paste")
			(net "VR_FET_SW_P12V_STBY_PVDDQ_GHJ")
		)
		(pad "2" smd rect
			(at 0 0.9652 90)
			(size 1.397 1.143)
			(layers "F.Cu" "F.Mask" "F.Paste")
			(net "GND")
		)
	)
	(footprint ""
		(layer "F.Cu")
		(at 24.8412 -69.3166 90)
		(property "Reference" "Q1D3"
			(at -1.34747 -0.1016 0)
			(unlocked yes)
			(layer "F.SilkS")
			(effects
				(font
					(size 0.7874 0.5842)
					(thickness 0.1524)
				)
				(justify left)
			)
		)
		(property "Value" ""
			(at 0 0 90)
			(layer "F.Fab")
			(effects
				(font
					(size 1.27 1.27)
				)
			)
		)
		(duplicate_pad_numbers_are_jumpers no)
		(fp_line
			(start 1.778 -0.5715)
			(end 1.778 0.3175)
			(stroke
				(width 0.1524)
				(type default)
			)
			(layer "F.SilkS")
		)
		(fp_line
			(start 0.9525 -0.5715)
			(end 1.778 -0.5715)
			(stroke
				(width 0.1524)
				(type default)
			)
			(layer "F.SilkS")
		)
		(fp_line
			(start 0.381 0.635)
			(end 0.381 1.27)
			(stroke
				(width 0.1524)
				(type default)
			)
			(layer "F.SilkS")
		)
		(fp_line
			(start 1.778 2.4765)
			(end 1.778 1.5875)
			(stroke
				(width 0.1524)
				(type default)
			)
			(layer "F.SilkS")
		)
		(fp_line
			(start 0.9525 2.4765)
			(end 1.778 2.4765)
			(stroke
				(width 0.1524)
				(type default)
			)
			(layer "F.SilkS")
		)
		(fp_circle
			(center -1.039368 -0.232156)
			(end -1.039368 -0.105156)
			(stroke
				(width 0.254)
				(type default)
			)
			(fill no)
			(layer "F.SilkS")
		)
		(fp_poly
			(pts
				(xy 1.778 2.4765) (xy 0.381 2.4765) (xy 0.381 -0.5715) (xy 1.778 -0.5715)
			)
			(stroke
				(width 0)
				(type default)
			)
			(fill no)
			(layer "F.CrtYd")
		)
		(fp_line
			(start 1.778 -0.5715)
			(end 0.381 -0.5715)
			(stroke
				(width 0.1)
				(type default)
			)
			(layer "F.Fab")
		)
		(fp_line
			(start 0.381 -0.5715)
			(end 0.381 2.4765)
			(stroke
				(width 0.1)
				(type default)
			)
			(layer "F.Fab")
		)
		(fp_line
			(start 1.778 2.4765)
			(end 1.778 -0.5715)
			(stroke
				(width 0.1)
				(type default)
			)
			(layer "F.Fab")
		)
		(fp_line
			(start 0.381 2.4765)
			(end 1.778 2.4765)
			(stroke
				(width 0.1)
				(type default)
			)
			(layer "F.Fab")
		)
		(fp_circle
			(center -0.9525 -0.9271)
			(end -0.9525 -0.8001)
			(stroke
				(width 0.254)
				(type default)
			)
			(fill no)
			(layer "F.Fab")
		)
		(pad "1" smd rect
			(at 0 0 90)
			(size 1.143 0.508)
			(layers "F.Cu" "F.Mask" "F.Paste")
			(net "TEMP_SENSOR_B")
		)
		(pad "2" smd rect
			(at 0 1.905 90)
			(size 1.143 0.508)
			(layers "F.Cu" "F.Mask" "F.Paste")
			(net "TEMP_SENSOR_E")
		)
		(pad "3" smd rect
			(at 2.159 0.9525 90)
			(size 1.143 0.508)
			(layers "F.Cu" "F.Mask" "F.Paste")
			(net "TEMP_SENSOR_B")
		)
	)
	(footprint ""
		(layer "F.Cu")
		(at 349.6437 -27.9654 180)
		(property "Reference" "C7F6"
			(at 0 0 180)
			(layer "F.SilkS")
			(hide yes)
			(effects
				(font
					(size 1.27 1.27)
				)
			)
		)
		(property "Value" ""
			(at 0 0 180)
			(layer "F.Fab")
			(effects
				(font
					(size 1.27 1.27)
				)
			)
		)
		(duplicate_pad_numbers_are_jumpers no)
		(fp_rect
			(start -0.3048 -0.1016)
			(end 0.3048 0.9906)
			(stroke
				(width 0)
				(type default)
			)
			(fill no)
			(layer "F.CrtYd")
		)
		(fp_line
			(start 0.3048 0.9906)
			(end 0.3048 -0.1016)
			(stroke
				(width 0.1)
				(type default)
			)
			(layer "F.Fab")
		)
		(fp_line
			(start 0.3048 -0.1016)
			(end -0.3048 -0.1016)
			(stroke
				(width 0.1)
				(type default)
			)
			(layer "F.Fab")
		)
		(fp_line
			(start -0.3048 0.9906)
			(end 0.3048 0.9906)
			(stroke
				(width 0.1)
				(type default)
			)
			(layer "F.Fab")
		)
		(fp_line
			(start -0.3048 -0.1016)
			(end -0.3048 0.9906)
			(stroke
				(width 0.1)
				(type default)
			)
			(layer "F.Fab")
		)
		(pad "1" smd rect
			(at 0 0 180)
			(size 0.508 0.508)
			(layers "F.Cu" "F.Mask" "F.Paste")
			(net "VR_FET_SW_P12V_STBY_PVPP_ABC")
		)
		(pad "2" smd rect
			(at 0 0.889 180)
			(size 0.508 0.508)
			(layers "F.Cu" "F.Mask" "F.Paste")
			(net "GND")
		)
		(zone
			(layer "F.Cu")
			(hatch none 0.5)
			(connect_pads
				(clearance 0)
			)
			(min_thickness 0.25)
			(keepout
				(tracks not_allowed)
				(vias allowed)
				(pads allowed)
				(copperpour not_allowed)
				(footprints allowed)
			)
			(placement
				(enabled no)
				(sheetname "")
			)
			(fill
				(thermal_gap 0.5)
				(thermal_bridge_width 0.5)
				(island_removal_mode 0)
			)
			(polygon
				(pts
					(xy 349.8977 -28.2194) (xy 349.8977 -28.6004) (xy 349.3897 -28.6004) (xy 349.3897 -28.2194)
				)
			)
		)
		(zone
			(layer "F.Cu")
			(hatch none 0.5)
			(connect_pads
				(clearance 0)
			)
			(min_thickness 0.25)
			(keepout
				(tracks allowed)
				(vias not_allowed)
				(pads allowed)
				(copperpour not_allowed)
				(footprints allowed)
			)
			(placement
				(enabled no)
				(sheetname "")
			)
			(fill
				(thermal_gap 0.5)
				(thermal_bridge_width 0.5)
				(island_removal_mode 0)
			)
			(polygon
				(pts
					(xy 349.8977 -28.2194) (xy 349.8977 -28.6004) (xy 349.3897 -28.6004) (xy 349.3897 -28.2194)
				)
			)
		)
	)
)
